(kicad_pcb
	(version 20260206)
	(generator "pcbnew")
	(generator_version "10.0")
	(general
		(thickness 1.6)
		(legacy_teardrops no)
	)
	(paper "A4")
	(title_block
		(title "01162023_DA0F0TEBIF0_F0T_Expander_BD_F_brd_V02_OCP.brd")
		(comment 1 "Grand Teton / footprint 4451 of 9728 (PEX3), pads 1190-1307 of 2397")
	)
	(layers
		(0 "F.Cu" signal "TOP")
		(4 "In1.Cu" signal "GND")
		(6 "In2.Cu" signal "VCC")
		(8 "In3.Cu" signal "VCC1")
		(10 "In4.Cu" signal "GND1")
		(12 "In5.Cu" signal "IN1")
		(14 "In6.Cu" signal "GND2")
		(16 "In7.Cu" signal "IN2")
		(18 "In8.Cu" signal "GND3")
		(20 "In9.Cu" signal "IN3")
		(22 "In10.Cu" signal "GND4")
		(24 "In11.Cu" signal "IN4")
		(26 "In12.Cu" signal "GND5")
		(28 "In13.Cu" signal "IN5")
		(30 "In14.Cu" signal "GND6")
		(32 "In15.Cu" signal "IN6")
		(34 "In16.Cu" signal "GND7")
		(2 "B.Cu" signal "BOTTOM")
		(9 "F.Adhes" user "F.Adhesive")
		(11 "B.Adhes" user "B.Adhesive")
		(13 "F.Paste" user "Package Geometry/Pastemask Top")
		(15 "B.Paste" user "Package Geometry/Pastemask Bottom")
		(5 "F.SilkS" user "Ref Des/Silkscreen Top")
		(7 "B.SilkS" user "Ref Des/Silkscreen Bottom")
		(1 "F.Mask" user "Board Geometry/Soldermask Top")
		(3 "B.Mask" user "Board Geometry/Soldermask Bottom")
		(17 "Dwgs.User" user "User.Drawings")
		(19 "Cmts.User" user "User.Comments")
		(21 "Eco1.User" user "User.Eco1")
		(23 "Eco2.User" user "User.Eco2")
		(25 "Edge.Cuts" user "Board Geometry/Outline")
		(27 "Margin" user)
		(31 "F.CrtYd" user "Package Geometry/Place Bound Top")
		(29 "B.CrtYd" user "Package Geometry/Place Bound Bottom")
		(35 "F.Fab" user "Ref Des/Assembly Top")
		(33 "B.Fab" user "Ref Des/Assembly Bottom")
	)
	(footprint ""
		(layer "F.Cu")
		(at 407.949908 -295.89984)
		(property "Reference" "PEX3"
			(at -3.358642 35.5727 0)
			(unlocked yes)
			(layer "F.SilkS")
			(effects
				(font
					(size 2.032 1.524)
					(thickness 0.1524)
				)
				(justify left)
			)
		)
		(property "Value" ""
			(at 0 0 0)
			(layer "F.Fab")
			(effects
				(font
					(size 1.27 1.27)
				)
			)
		)
		(duplicate_pad_numbers_are_jumpers no)
		(pad "BC16" smd circle
			(at -8.549894 17.100042)
			(size 0.4572 0.4572)
			(layers "F.Cu" "F.Mask" "F.Paste")
			(net "GND")
		)
		(pad "BC17" smd circle
			(at -7.599934 17.100042)
			(size 0.4572 0.4572)
			(layers "F.Cu" "F.Mask" "F.Paste")
			(net "P5E_PEX3_STN2_TX_DP<39>")
		)
		(pad "BC18" smd circle
			(at -6.649974 17.100042)
			(size 0.4572 0.4572)
			(layers "F.Cu" "F.Mask" "F.Paste")
			(net "GND")
		)
		(pad "BC19" smd circle
			(at -5.700014 17.100042)
			(size 0.4572 0.4572)
			(layers "F.Cu" "F.Mask" "F.Paste")
			(net "P5E_PEX3_STN2_TX_DP<37>")
		)
		(pad "BC20" smd circle
			(at -4.750054 17.100042)
			(size 0.4572 0.4572)
			(layers "F.Cu" "F.Mask" "F.Paste")
			(net "GND")
		)
		(pad "BC21" smd circle
			(at -3.800094 17.100042)
			(size 0.4572 0.4572)
			(layers "F.Cu" "F.Mask" "F.Paste")
			(net "P5E_PEX3_STN2_TX_DP<35>")
		)
		(pad "BC22" smd circle
			(at -2.84988 17.100042)
			(size 0.4572 0.4572)
			(layers "F.Cu" "F.Mask" "F.Paste")
			(net "GND")
		)
		(pad "BC23" smd circle
			(at -1.89992 17.100042)
			(size 0.4572 0.4572)
			(layers "F.Cu" "F.Mask" "F.Paste")
			(net "P5E_PEX3_STN2_TX_DP<33>")
		)
		(pad "BC24" smd circle
			(at -0.94996 17.100042)
			(size 0.4572 0.4572)
			(layers "F.Cu" "F.Mask" "F.Paste")
			(net "GND")
		)
		(pad "BC25" smd circle
			(at 0 17.100042)
			(size 0.4572 0.4572)
			(layers "F.Cu" "F.Mask" "F.Paste")
			(net "P5E_PEX3_STN1_TX_DP<16>")
		)
		(pad "BC26" smd circle
			(at 0.94996 17.100042)
			(size 0.4572 0.4572)
			(layers "F.Cu" "F.Mask" "F.Paste")
			(net "GND")
		)
		(pad "BC27" smd circle
			(at 1.89992 17.100042)
			(size 0.4572 0.4572)
			(layers "F.Cu" "F.Mask" "F.Paste")
			(net "P5E_PEX3_STN1_TX_DP<18>")
		)
		(pad "BC28" smd circle
			(at 2.84988 17.100042)
			(size 0.4572 0.4572)
			(layers "F.Cu" "F.Mask" "F.Paste")
			(net "GND")
		)
		(pad "BC29" smd circle
			(at 3.800094 17.100042)
			(size 0.4572 0.4572)
			(layers "F.Cu" "F.Mask" "F.Paste")
			(net "P5E_PEX3_STN1_TX_DP<20>")
		)
		(pad "BC30" smd circle
			(at 4.750054 17.100042)
			(size 0.4572 0.4572)
			(layers "F.Cu" "F.Mask" "F.Paste")
			(net "GND")
		)
		(pad "BC31" smd circle
			(at 5.700014 17.100042)
			(size 0.4572 0.4572)
			(layers "F.Cu" "F.Mask" "F.Paste")
			(net "P5E_PEX3_STN1_TX_DP<22>")
		)
		(pad "BC32" smd circle
			(at 6.649974 17.100042)
			(size 0.4572 0.4572)
			(layers "F.Cu" "F.Mask" "F.Paste")
			(net "GND")
		)
		(pad "BC33" smd circle
			(at 7.599934 17.100042)
			(size 0.4572 0.4572)
			(layers "F.Cu" "F.Mask" "F.Paste")
			(net "P5E_PEX3_STN1_TX_DP<24>")
		)
		(pad "BC34" smd circle
			(at 8.549894 17.100042)
			(size 0.4572 0.4572)
			(layers "F.Cu" "F.Mask" "F.Paste")
			(net "GND")
		)
		(pad "BC35" smd circle
			(at 9.500108 17.100042)
			(size 0.4572 0.4572)
			(layers "F.Cu" "F.Mask" "F.Paste")
			(net "P5E_PEX3_STN1_TX_DP<26>")
		)
		(pad "BC36" smd circle
			(at 10.450068 17.100042)
			(size 0.4572 0.4572)
			(layers "F.Cu" "F.Mask" "F.Paste")
			(net "GND")
		)
		(pad "BC37" smd circle
			(at 11.400028 17.100042)
			(size 0.4572 0.4572)
			(layers "F.Cu" "F.Mask" "F.Paste")
			(net "P5E_PEX3_STN1_TX_DP<28>")
		)
		(pad "BC38" smd circle
			(at 12.349988 17.100042)
			(size 0.4572 0.4572)
			(layers "F.Cu" "F.Mask" "F.Paste")
			(net "GND")
		)
		(pad "BC39" smd circle
			(at 13.299948 17.100042)
			(size 0.4572 0.4572)
			(layers "F.Cu" "F.Mask" "F.Paste")
			(net "P5E_PEX3_STN1_TX_DP<30>")
		)
		(pad "BC40" smd circle
			(at 14.249908 17.100042)
			(size 0.4572 0.4572)
			(layers "F.Cu" "F.Mask" "F.Paste")
			(net "GND")
		)
		(pad "BC41" smd circle
			(at 15.200122 17.100042)
			(size 0.4572 0.4572)
			(layers "F.Cu" "F.Mask" "F.Paste")
			(net "P5E_PEX3_STN0_TX_DP<15>")
		)
		(pad "BC42" smd circle
			(at 16.150082 17.100042)
			(size 0.4572 0.4572)
			(layers "F.Cu" "F.Mask" "F.Paste")
			(net "GND")
		)
		(pad "BC43" smd circle
			(at 17.100042 17.100042)
			(size 0.4572 0.4572)
			(layers "F.Cu" "F.Mask" "F.Paste")
			(net "P5E_PEX3_STN0_TX_DP<13>")
		)
		(pad "BC44" smd circle
			(at 18.050002 17.100042)
			(size 0.4572 0.4572)
			(layers "F.Cu" "F.Mask" "F.Paste")
			(net "GND")
		)
		(pad "BC45" smd circle
			(at 18.999962 17.100042)
			(size 0.4572 0.4572)
			(layers "F.Cu" "F.Mask" "F.Paste")
			(net "P5E_PEX3_STN0_TX_DP<11>")
		)
		(pad "BC46" smd circle
			(at 19.949922 17.100042)
			(size 0.4572 0.4572)
			(layers "F.Cu" "F.Mask" "F.Paste")
			(net "GND")
		)
		(pad "BC47" smd circle
			(at 20.899882 17.100042)
			(size 0.4572 0.4572)
			(layers "F.Cu" "F.Mask" "F.Paste")
			(net "P5E_PEX3_STN0_TX_DP<9>")
		)
		(pad "BC48" smd circle
			(at 21.850096 17.100042)
			(size 0.4572 0.4572)
			(layers "F.Cu" "F.Mask" "F.Paste")
			(net "GND")
		)
		(pad "BC49" smd circle
			(at 22.800056 17.100042)
			(size 0.4572 0.4572)
			(layers "F.Cu" "F.Mask" "F.Paste")
			(net "GND")
		)
		(pad "BD1" smd circle
			(at -22.800056 18.050002)
			(size 0.4572 0.4572)
			(layers "F.Cu" "F.Mask" "F.Paste")
			(net "GND")
		)
		(pad "BD2" smd circle
			(at -21.850096 18.050002)
			(size 0.4572 0.4572)
			(layers "F.Cu" "F.Mask" "F.Paste")
			(net "GND")
		)
		(pad "BD3" smd circle
			(at -20.899882 18.050002)
			(size 0.4572 0.4572)
			(layers "F.Cu" "F.Mask" "F.Paste")
			(net "Net_1434")
		)
		(pad "BD4" smd circle
			(at -19.949922 18.050002)
			(size 0.4572 0.4572)
			(layers "F.Cu" "F.Mask" "F.Paste")
			(net "GND")
		)
		(pad "BD5" smd circle
			(at -18.999962 18.050002)
			(size 0.4572 0.4572)
			(layers "F.Cu" "F.Mask" "F.Paste")
			(net "Net_1465")
		)
		(pad "BD6" smd circle
			(at -18.050002 18.050002)
			(size 0.4572 0.4572)
			(layers "F.Cu" "F.Mask" "F.Paste")
			(net "GND")
		)
		(pad "BD7" smd circle
			(at -17.100042 18.050002)
			(size 0.4572 0.4572)
			(layers "F.Cu" "F.Mask" "F.Paste")
			(net "Net_1395")
		)
		(pad "BD8" smd circle
			(at -16.150082 18.050002)
			(size 0.4572 0.4572)
			(layers "F.Cu" "F.Mask" "F.Paste")
			(net "GND")
		)
		(pad "BD9" smd circle
			(at -15.200122 18.050002)
			(size 0.4572 0.4572)
			(layers "F.Cu" "F.Mask" "F.Paste")
			(net "P5E_PEX3_STN2_TX_DN<47>")
		)
		(pad "BD10" smd circle
			(at -14.249908 18.050002)
			(size 0.4572 0.4572)
			(layers "F.Cu" "F.Mask" "F.Paste")
			(net "GND")
		)
		(pad "BD11" smd circle
			(at -13.299948 18.050002)
			(size 0.4572 0.4572)
			(layers "F.Cu" "F.Mask" "F.Paste")
			(net "P5E_PEX3_STN2_TX_DN<45>")
		)
		(pad "BD12" smd circle
			(at -12.349988 18.050002)
			(size 0.4572 0.4572)
			(layers "F.Cu" "F.Mask" "F.Paste")
			(net "GND")
		)
		(pad "BD13" smd circle
			(at -11.400028 18.050002)
			(size 0.4572 0.4572)
			(layers "F.Cu" "F.Mask" "F.Paste")
			(net "P5E_PEX3_STN2_TX_DN<43>")
		)
		(pad "BD14" smd circle
			(at -10.450068 18.050002)
			(size 0.4572 0.4572)
			(layers "F.Cu" "F.Mask" "F.Paste")
			(net "GND")
		)
		(pad "BD15" smd circle
			(at -9.500108 18.050002)
			(size 0.4572 0.4572)
			(layers "F.Cu" "F.Mask" "F.Paste")
			(net "P5E_PEX3_STN2_TX_DN<41>")
		)
		(pad "BD16" smd circle
			(at -8.549894 18.050002)
			(size 0.4572 0.4572)
			(layers "F.Cu" "F.Mask" "F.Paste")
			(net "GND")
		)
		(pad "BD17" smd circle
			(at -7.599934 18.050002)
			(size 0.4572 0.4572)
			(layers "F.Cu" "F.Mask" "F.Paste")
			(net "P5E_PEX3_STN2_TX_DN<39>")
		)
		(pad "BD18" smd circle
			(at -6.649974 18.050002)
			(size 0.4572 0.4572)
			(layers "F.Cu" "F.Mask" "F.Paste")
			(net "GND")
		)
		(pad "BD19" smd circle
			(at -5.700014 18.050002)
			(size 0.4572 0.4572)
			(layers "F.Cu" "F.Mask" "F.Paste")
			(net "P5E_PEX3_STN2_TX_DN<37>")
		)
		(pad "BD20" smd circle
			(at -4.750054 18.050002)
			(size 0.4572 0.4572)
			(layers "F.Cu" "F.Mask" "F.Paste")
			(net "GND")
		)
		(pad "BD21" smd circle
			(at -3.800094 18.050002)
			(size 0.4572 0.4572)
			(layers "F.Cu" "F.Mask" "F.Paste")
			(net "P5E_PEX3_STN2_TX_DN<35>")
		)
		(pad "BD22" smd circle
			(at -2.84988 18.050002)
			(size 0.4572 0.4572)
			(layers "F.Cu" "F.Mask" "F.Paste")
			(net "GND")
		)
		(pad "BD23" smd circle
			(at -1.89992 18.050002)
			(size 0.4572 0.4572)
			(layers "F.Cu" "F.Mask" "F.Paste")
			(net "P5E_PEX3_STN2_TX_DN<33>")
		)
		(pad "BD24" smd circle
			(at -0.94996 18.050002)
			(size 0.4572 0.4572)
			(layers "F.Cu" "F.Mask" "F.Paste")
			(net "GND")
		)
		(pad "BD25" smd circle
			(at 0 18.050002)
			(size 0.4572 0.4572)
			(layers "F.Cu" "F.Mask" "F.Paste")
			(net "P5E_PEX3_STN1_TX_DN<16>")
		)
		(pad "BD26" smd circle
			(at 0.94996 18.050002)
			(size 0.4572 0.4572)
			(layers "F.Cu" "F.Mask" "F.Paste")
			(net "GND")
		)
		(pad "BD27" smd circle
			(at 1.89992 18.050002)
			(size 0.4572 0.4572)
			(layers "F.Cu" "F.Mask" "F.Paste")
			(net "P5E_PEX3_STN1_TX_DN<18>")
		)
		(pad "BD28" smd circle
			(at 2.84988 18.050002)
			(size 0.4572 0.4572)
			(layers "F.Cu" "F.Mask" "F.Paste")
			(net "GND")
		)
		(pad "BD29" smd circle
			(at 3.800094 18.050002)
			(size 0.4572 0.4572)
			(layers "F.Cu" "F.Mask" "F.Paste")
			(net "P5E_PEX3_STN1_TX_DN<20>")
		)
		(pad "BD30" smd circle
			(at 4.750054 18.050002)
			(size 0.4572 0.4572)
			(layers "F.Cu" "F.Mask" "F.Paste")
			(net "GND")
		)
		(pad "BD31" smd circle
			(at 5.700014 18.050002)
			(size 0.4572 0.4572)
			(layers "F.Cu" "F.Mask" "F.Paste")
			(net "P5E_PEX3_STN1_TX_DN<22>")
		)
		(pad "BD32" smd circle
			(at 6.649974 18.050002)
			(size 0.4572 0.4572)
			(layers "F.Cu" "F.Mask" "F.Paste")
			(net "GND")
		)
		(pad "BD33" smd circle
			(at 7.599934 18.050002)
			(size 0.4572 0.4572)
			(layers "F.Cu" "F.Mask" "F.Paste")
			(net "P5E_PEX3_STN1_TX_DN<24>")
		)
		(pad "BD34" smd circle
			(at 8.549894 18.050002)
			(size 0.4572 0.4572)
			(layers "F.Cu" "F.Mask" "F.Paste")
			(net "GND")
		)
		(pad "BD35" smd circle
			(at 9.500108 18.050002)
			(size 0.4572 0.4572)
			(layers "F.Cu" "F.Mask" "F.Paste")
			(net "P5E_PEX3_STN1_TX_DN<26>")
		)
		(pad "BD36" smd circle
			(at 10.450068 18.050002)
			(size 0.4572 0.4572)
			(layers "F.Cu" "F.Mask" "F.Paste")
			(net "GND")
		)
		(pad "BD37" smd circle
			(at 11.400028 18.050002)
			(size 0.4572 0.4572)
			(layers "F.Cu" "F.Mask" "F.Paste")
			(net "P5E_PEX3_STN1_TX_DN<28>")
		)
		(pad "BD38" smd circle
			(at 12.349988 18.050002)
			(size 0.4572 0.4572)
			(layers "F.Cu" "F.Mask" "F.Paste")
			(net "GND")
		)
		(pad "BD39" smd circle
			(at 13.299948 18.050002)
			(size 0.4572 0.4572)
			(layers "F.Cu" "F.Mask" "F.Paste")
			(net "P5E_PEX3_STN1_TX_DN<30>")
		)
		(pad "BD40" smd circle
			(at 14.249908 18.050002)
			(size 0.4572 0.4572)
			(layers "F.Cu" "F.Mask" "F.Paste")
			(net "GND")
		)
		(pad "BD41" smd circle
			(at 15.200122 18.050002)
			(size 0.4572 0.4572)
			(layers "F.Cu" "F.Mask" "F.Paste")
			(net "P5E_PEX3_STN0_TX_DN<15>")
		)
		(pad "BD42" smd circle
			(at 16.150082 18.050002)
			(size 0.4572 0.4572)
			(layers "F.Cu" "F.Mask" "F.Paste")
			(net "GND")
		)
		(pad "BD43" smd circle
			(at 17.100042 18.050002)
			(size 0.4572 0.4572)
			(layers "F.Cu" "F.Mask" "F.Paste")
			(net "P5E_PEX3_STN0_TX_DN<13>")
		)
		(pad "BD44" smd circle
			(at 18.050002 18.050002)
			(size 0.4572 0.4572)
			(layers "F.Cu" "F.Mask" "F.Paste")
			(net "GND")
		)
		(pad "BD45" smd circle
			(at 18.999962 18.050002)
			(size 0.4572 0.4572)
			(layers "F.Cu" "F.Mask" "F.Paste")
			(net "P5E_PEX3_STN0_TX_DN<11>")
		)
		(pad "BD46" smd circle
			(at 19.949922 18.050002)
			(size 0.4572 0.4572)
			(layers "F.Cu" "F.Mask" "F.Paste")
			(net "GND")
		)
		(pad "BD47" smd circle
			(at 20.899882 18.050002)
			(size 0.4572 0.4572)
			(layers "F.Cu" "F.Mask" "F.Paste")
			(net "P5E_PEX3_STN0_TX_DN<9>")
		)
		(pad "BD48" smd circle
			(at 21.850096 18.050002)
			(size 0.4572 0.4572)
			(layers "F.Cu" "F.Mask" "F.Paste")
			(net "GND")
		)
		(pad "BD49" smd circle
			(at 22.800056 18.050002)
			(size 0.4572 0.4572)
			(layers "F.Cu" "F.Mask" "F.Paste")
			(net "GND")
		)
		(pad "BE1" smd circle
			(at -22.800056 18.999962)
			(size 0.4572 0.4572)
			(layers "F.Cu" "F.Mask" "F.Paste")
			(net "Net_1455")
		)
		(pad "BE2" smd circle
			(at -21.850096 18.999962)
			(size 0.4572 0.4572)
			(layers "F.Cu" "F.Mask" "F.Paste")
			(net "Net_1423")
		)
		(pad "BE3" smd circle
			(at -20.899882 18.999962)
			(size 0.4572 0.4572)
			(layers "F.Cu" "F.Mask" "F.Paste")
			(net "GND")
		)
		(pad "BE4" smd circle
			(at -19.949922 18.999962)
			(size 0.4572 0.4572)
			(layers "F.Cu" "F.Mask" "F.Paste")
			(net "GND")
		)
		(pad "BE5" smd circle
			(at -18.999962 18.999962)
			(size 0.4572 0.4572)
			(layers "F.Cu" "F.Mask" "F.Paste")
			(net "GND")
		)
		(pad "BE6" smd circle
			(at -18.050002 18.999962)
			(size 0.4572 0.4572)
			(layers "F.Cu" "F.Mask" "F.Paste")
			(net "GND")
		)
		(pad "BE7" smd circle
			(at -17.100042 18.999962)
			(size 0.4572 0.4572)
			(layers "F.Cu" "F.Mask" "F.Paste")
			(net "GND")
		)
		(pad "BE8" smd circle
			(at -16.150082 18.999962)
			(size 0.4572 0.4572)
			(layers "F.Cu" "F.Mask" "F.Paste")
			(net "GND")
		)
		(pad "BE9" smd circle
			(at -15.200122 18.999962)
			(size 0.4572 0.4572)
			(layers "F.Cu" "F.Mask" "F.Paste")
			(net "GND")
		)
		(pad "BE10" smd circle
			(at -14.249908 18.999962)
			(size 0.4572 0.4572)
			(layers "F.Cu" "F.Mask" "F.Paste")
			(net "GND")
		)
		(pad "BE11" smd circle
			(at -13.299948 18.999962)
			(size 0.4572 0.4572)
			(layers "F.Cu" "F.Mask" "F.Paste")
			(net "GND")
		)
		(pad "BE12" smd circle
			(at -12.349988 18.999962)
			(size 0.4572 0.4572)
			(layers "F.Cu" "F.Mask" "F.Paste")
			(net "GND")
		)
		(pad "BE13" smd circle
			(at -11.400028 18.999962)
			(size 0.4572 0.4572)
			(layers "F.Cu" "F.Mask" "F.Paste")
			(net "GND")
		)
		(pad "BE14" smd circle
			(at -10.450068 18.999962)
			(size 0.4572 0.4572)
			(layers "F.Cu" "F.Mask" "F.Paste")
			(net "GND")
		)
		(pad "BE15" smd circle
			(at -9.500108 18.999962)
			(size 0.4572 0.4572)
			(layers "F.Cu" "F.Mask" "F.Paste")
			(net "GND")
		)
		(pad "BE16" smd circle
			(at -8.549894 18.999962)
			(size 0.4572 0.4572)
			(layers "F.Cu" "F.Mask" "F.Paste")
			(net "GND")
		)
		(pad "BE17" smd circle
			(at -7.599934 18.999962)
			(size 0.4572 0.4572)
			(layers "F.Cu" "F.Mask" "F.Paste")
			(net "GND")
		)
		(pad "BE18" smd circle
			(at -6.649974 18.999962)
			(size 0.4572 0.4572)
			(layers "F.Cu" "F.Mask" "F.Paste")
			(net "GND")
		)
		(pad "BE19" smd circle
			(at -5.700014 18.999962)
			(size 0.4572 0.4572)
			(layers "F.Cu" "F.Mask" "F.Paste")
			(net "GND")
		)
		(pad "BE20" smd circle
			(at -4.750054 18.999962)
			(size 0.4572 0.4572)
			(layers "F.Cu" "F.Mask" "F.Paste")
			(net "GND")
		)
		(pad "BE21" smd circle
			(at -3.800094 18.999962)
			(size 0.4572 0.4572)
			(layers "F.Cu" "F.Mask" "F.Paste")
			(net "GND")
		)
		(pad "BE22" smd circle
			(at -2.84988 18.999962)
			(size 0.4572 0.4572)
			(layers "F.Cu" "F.Mask" "F.Paste")
			(net "GND")
		)
		(pad "BE23" smd circle
			(at -1.89992 18.999962)
			(size 0.4572 0.4572)
			(layers "F.Cu" "F.Mask" "F.Paste")
			(net "GND")
		)
		(pad "BE24" smd circle
			(at -0.94996 18.999962)
			(size 0.4572 0.4572)
			(layers "F.Cu" "F.Mask" "F.Paste")
			(net "GND")
		)
		(pad "BE25" smd circle
			(at 0 18.999962)
			(size 0.4572 0.4572)
			(layers "F.Cu" "F.Mask" "F.Paste")
			(net "GND")
		)
		(pad "BE26" smd circle
			(at 0.94996 18.999962)
			(size 0.4572 0.4572)
			(layers "F.Cu" "F.Mask" "F.Paste")
			(net "GND")
		)
		(pad "BE27" smd circle
			(at 1.89992 18.999962)
			(size 0.4572 0.4572)
			(layers "F.Cu" "F.Mask" "F.Paste")
			(net "GND")
		)
		(pad "BE28" smd circle
			(at 2.84988 18.999962)
			(size 0.4572 0.4572)
			(layers "F.Cu" "F.Mask" "F.Paste")
			(net "GND")
		)
		(pad "BE29" smd circle
			(at 3.800094 18.999962)
			(size 0.4572 0.4572)
			(layers "F.Cu" "F.Mask" "F.Paste")
			(net "GND")
		)
		(pad "BE30" smd circle
			(at 4.750054 18.999962)
			(size 0.4572 0.4572)
			(layers "F.Cu" "F.Mask" "F.Paste")
			(net "GND")
		)
		(pad "BE31" smd circle
			(at 5.700014 18.999962)
			(size 0.4572 0.4572)
			(layers "F.Cu" "F.Mask" "F.Paste")
			(net "GND")
		)
		(pad "BE32" smd circle
			(at 6.649974 18.999962)
			(size 0.4572 0.4572)
			(layers "F.Cu" "F.Mask" "F.Paste")
			(net "GND")
		)
		(pad "BE33" smd circle
			(at 7.599934 18.999962)
			(size 0.4572 0.4572)
			(layers "F.Cu" "F.Mask" "F.Paste")
			(net "GND")
		)
		(pad "BE34" smd circle
			(at 8.549894 18.999962)
			(size 0.4572 0.4572)
			(layers "F.Cu" "F.Mask" "F.Paste")
			(net "GND")
		)
		(pad "BE35" smd circle
			(at 9.500108 18.999962)
			(size 0.4572 0.4572)
			(layers "F.Cu" "F.Mask" "F.Paste")
			(net "GND")
		)
	)
)
